(kicad_pcb
	(version 20260206)
	(generator "pcbnew")
	(generator_version "10.0")
	(general
		(thickness 1.6)
		(legacy_teardrops no)
	)
	(paper "A4")
	(title_block
		(title "peb — Lightning_PEB_BRD.brd")
		(comment 1 "Lightning (Wiwynn / Facebook NVMe JBOF) / footprints 1446-1451 of 2563")
	)
	(layers
		(0 "F.Cu" signal "TOP")
		(4 "In1.Cu" signal "L2GND")
		(6 "In2.Cu" signal "L3")
		(8 "In3.Cu" signal "L4VCC")
		(10 "In4.Cu" signal "L5VCC")
		(12 "In5.Cu" signal "L6")
		(14 "In6.Cu" signal "L7GND")
		(2 "B.Cu" signal "BOTTOM")
		(9 "F.Adhes" user "F.Adhesive")
		(11 "B.Adhes" user "B.Adhesive")
		(13 "F.Paste" user "Package Geometry/Pastemask Top")
		(15 "B.Paste" user "Package Geometry/Pastemask Bottom")
		(5 "F.SilkS" user "Ref Des/Silkscreen Top")
		(7 "B.SilkS" user "Ref Des/Silkscreen Bottom")
		(1 "F.Mask" user "Board Geometry/Soldermask Top")
		(3 "B.Mask" user "Board Geometry/Soldermask Bottom")
		(17 "Dwgs.User" user "User.Drawings")
		(19 "Cmts.User" user "User.Comments")
		(21 "Eco1.User" user "User.Eco1")
		(23 "Eco2.User" user "User.Eco2")
		(25 "Edge.Cuts" user "Board Geometry/Outline")
		(27 "Margin" user)
		(31 "F.CrtYd" user "Package Geometry/Place Bound Top")
		(29 "B.CrtYd" user "Package Geometry/Place Bound Bottom")
		(35 "F.Fab" user "Ref Des/Assembly Top")
		(33 "B.Fab" user "Ref Des/Assembly Bottom")
	)
	(footprint ""
		(layer "F.Cu")
		(at 59.817 -119.126)
		(property "Reference" "G1"
			(at 0 0 0)
			(layer "F.SilkS")
			(hide yes)
			(effects
				(font
					(size 1.27 1.27)
				)
			)
		)
		(property "Value" "TPAD-JTAG-7P-GP"
			(at 0.0762 -11.5062 0)
			(unlocked yes)
			(layer "F.Fab")
			(hide yes)
			(effects
				(font
					(size 1.016 1.016)
					(thickness 0.1524)
				)
			)
		)
		(property "Device Type" "TPAD-JTAG-7P"
			(at 0.0762 -13.4112 0)
			(unlocked yes)
			(layer "F.Fab")
			(hide yes)
			(effects
				(font
					(size 1.016 1.016)
					(thickness 0.1524)
				)
			)
		)
		(duplicate_pad_numbers_are_jumpers no)
		(fp_line
			(start -1.0922 -8.4836)
			(end 1.0922 -8.4836)
			(stroke
				(width 0.1524)
				(type default)
			)
			(layer "F.SilkS")
		)
		(fp_line
			(start -1.0922 8.4836)
			(end -1.0922 -8.4836)
			(stroke
				(width 0.1524)
				(type default)
			)
			(layer "F.SilkS")
		)
		(fp_line
			(start 1.0922 -8.4836)
			(end 1.0922 8.4836)
			(stroke
				(width 0.1524)
				(type default)
			)
			(layer "F.SilkS")
		)
		(fp_line
			(start 1.0922 8.4836)
			(end -1.0922 8.4836)
			(stroke
				(width 0.1524)
				(type default)
			)
			(layer "F.SilkS")
		)
		(fp_rect
			(start -1.1684 8.5598)
			(end 1.1684 -8.5598)
			(stroke
				(width 0)
				(type default)
			)
			(fill no)
			(layer "F.CrtYd")
		)
		(fp_poly
			(pts
				(xy -1.3462 -8.7376) (xy 1.3462 -8.7376) (xy 1.3462 8.7376) (xy -1.3462 8.7376)
			)
			(stroke
				(width 0)
				(type default)
			)
			(fill no)
			(layer "F.Fab")
		)
		(pad "1" smd rect
			(at 0 -7.62)
			(size 1.4986 0.9906)
			(layers "F.Cu" "F.Mask" "F.Paste")
			(net "JTAG_BMC_TRST_N")
		)
		(pad "2" smd rect
			(at 0 -5.08)
			(size 1.4986 0.9906)
			(layers "F.Cu" "F.Mask" "F.Paste")
			(net "JTAG_BMC_TDI")
		)
		(pad "3" smd rect
			(at 0 -2.54)
			(size 1.4986 0.9906)
			(layers "F.Cu" "F.Mask" "F.Paste")
			(net "JTAG_BMC_TMS")
		)
		(pad "4" smd rect
			(at 0 0)
			(size 1.4986 0.9906)
			(layers "F.Cu" "F.Mask" "F.Paste")
			(net "JTAG_BMC_TCK")
		)
		(pad "5" smd rect
			(at 0 2.54)
			(size 1.4986 0.9906)
			(layers "F.Cu" "F.Mask" "F.Paste")
			(net "BMC0_JTAG_RTCK")
		)
		(pad "6" smd rect
			(at 0 5.08)
			(size 1.4986 0.9906)
			(layers "F.Cu" "F.Mask" "F.Paste")
			(net "JTAG_BMC_TDO")
		)
		(pad "7" smd rect
			(at 0 7.62)
			(size 1.4986 0.9906)
			(layers "F.Cu" "F.Mask" "F.Paste")
			(net "FM_BMC_RESET_N")
		)
	)
	(footprint ""
		(layer "F.Cu")
		(at 214.948008 -4.064)
		(property "Reference" "R675"
			(at 0 0 0)
			(layer "F.SilkS")
			(hide yes)
			(effects
				(font
					(size 1.27 1.27)
				)
			)
		)
		(property "Value" "100KR2F-L1-GP"
			(at 0.064008 -3.993896 0)
			(unlocked yes)
			(layer "F.Fab")
			(hide yes)
			(effects
				(font
					(size 1.016 1.016)
					(thickness 0.1524)
				)
			)
		)
		(property "Device Type" "R402H16"
			(at 0.064008 -5.517896 0)
			(unlocked yes)
			(layer "F.Fab")
			(hide yes)
			(effects
				(font
					(size 1.016 1.016)
					(thickness 0.1524)
				)
			)
		)
		(duplicate_pad_numbers_are_jumpers no)
		(fp_line
			(start -0.508 -0.9398)
			(end -0.508 0.9398)
			(stroke
				(width 0.1524)
				(type default)
			)
			(layer "F.SilkS")
		)
		(fp_line
			(start 0.508 -0.9398)
			(end -0.508 -0.9398)
			(stroke
				(width 0.1524)
				(type default)
			)
			(layer "F.SilkS")
		)
		(fp_rect
			(start -0.508 0.9398)
			(end 0.508 -0.9398)
			(stroke
				(width 0)
				(type default)
			)
			(fill no)
			(layer "F.CrtYd")
		)
		(fp_rect
			(start -0.508 0.9398)
			(end 0.508 -0.9398)
			(stroke
				(width 0)
				(type default)
			)
			(fill no)
			(layer "F.Fab")
		)
		(pad "1" smd custom
			(at 0 -0.4445)
			(size 0.1397 0.1397)
			(layers "F.Cu" "F.Mask" "F.Paste")
			(net "HOST2_RST_N")
			(options
				(clearance outline)
				(anchor circle)
			)
			(primitives
				(gr_poly
					(pts
						(arc
							(start -0.1778 -0.2794)
							(mid -0.249642 -0.249642)
							(end -0.2794 -0.1778)
						)
						(arc
							(start -0.2794 0.1778)
							(mid -0.249642 0.249642)
							(end -0.1778 0.2794)
						)
						(arc
							(start 0.1778 0.2794)
							(mid 0.249642 0.249642)
							(end 0.2794 0.1778)
						)
						(arc
							(start 0.2794 -0.1778)
							(mid 0.249642 -0.249642)
							(end 0.1778 -0.2794)
						)
					)
					(width 0)
					(fill yes)
				)
			)
		)
		(pad "2" smd custom
			(at 0 0.4445)
			(size 0.1397 0.1397)
			(layers "F.Cu" "F.Mask" "F.Paste")
			(net "GND")
			(options
				(clearance outline)
				(anchor circle)
			)
			(primitives
				(gr_poly
					(pts
						(arc
							(start -0.1778 -0.2794)
							(mid -0.249642 -0.249642)
							(end -0.2794 -0.1778)
						)
						(arc
							(start -0.2794 0.1778)
							(mid -0.249642 0.249642)
							(end -0.1778 0.2794)
						)
						(arc
							(start 0.1778 0.2794)
							(mid 0.249642 0.249642)
							(end 0.2794 0.1778)
						)
						(arc
							(start 0.2794 -0.1778)
							(mid 0.249642 -0.249642)
							(end 0.1778 -0.2794)
						)
					)
					(width 0)
					(fill yes)
				)
			)
		)
	)
	(footprint ""
		(layer "F.Cu")
		(at 140.8176 -86.6394)
		(property "Reference" "PC92"
			(at 0 0 0)
			(layer "F.SilkS")
			(hide yes)
			(effects
				(font
					(size 1.27 1.27)
				)
			)
		)
		(property "Value" "SC820P50V2KX-1GP"
			(at 1.1811 -2.7051 0)
			(unlocked yes)
			(layer "F.Fab")
			(hide yes)
			(effects
				(font
					(size 1.016 1.016)
					(thickness 0.1524)
				)
			)
		)
		(property "Device Type" "C402H22"
			(at 1.1811 -4.2291 0)
			(unlocked yes)
			(layer "F.Fab")
			(hide yes)
			(effects
				(font
					(size 1.016 1.016)
					(thickness 0.1524)
				)
			)
		)
		(duplicate_pad_numbers_are_jumpers no)
		(fp_rect
			(start -0.4318 0.9525)
			(end 0.4318 -0.9525)
			(stroke
				(width 0)
				(type default)
			)
			(fill no)
			(layer "F.CrtYd")
		)
		(fp_rect
			(start -0.4318 0.9525)
			(end 0.4318 -0.9525)
			(stroke
				(width 0)
				(type default)
			)
			(fill no)
			(layer "F.Fab")
		)
		(pad "1" smd custom
			(at 0 -0.4445)
			(size 0.1524 0.1524)
			(layers "F.Cu" "F.Mask" "F.Paste")
			(net "VR_P1V8_STBY_SS_C")
			(options
				(clearance outline)
				(anchor circle)
			)
			(primitives
				(gr_poly
					(pts
						(arc
							(start 0.3048 -0.2032)
							(mid 0.275042 -0.275042)
							(end 0.2032 -0.3048)
						)
						(arc
							(start -0.2032 -0.3048)
							(mid -0.275042 -0.275042)
							(end -0.3048 -0.2032)
						)
						(arc
							(start -0.3048 0.2032)
							(mid -0.275042 0.275042)
							(end -0.2032 0.3048)
						)
						(arc
							(start 0.2032 0.3048)
							(mid 0.275042 0.275042)
							(end 0.3048 0.2032)
						)
					)
					(width 0)
					(fill yes)
				)
			)
		)
		(pad "2" smd custom
			(at 0 0.4445)
			(size 0.1524 0.1524)
			(layers "F.Cu" "F.Mask" "F.Paste")
			(net "GND")
			(options
				(clearance outline)
				(anchor circle)
			)
			(primitives
				(gr_poly
					(pts
						(arc
							(start 0.3048 -0.2032)
							(mid 0.275042 -0.275042)
							(end 0.2032 -0.3048)
						)
						(arc
							(start -0.2032 -0.3048)
							(mid -0.275042 -0.275042)
							(end -0.3048 -0.2032)
						)
						(arc
							(start -0.3048 0.2032)
							(mid -0.275042 0.275042)
							(end -0.2032 0.3048)
						)
						(arc
							(start 0.2032 0.3048)
							(mid 0.275042 0.275042)
							(end 0.3048 0.2032)
						)
					)
					(width 0)
					(fill yes)
				)
			)
		)
	)
	(footprint ""
		(layer "F.Cu")
		(at 125.1204 -42.164 90)
		(property "Reference" "R932"
			(at 0 0 90)
			(layer "F.SilkS")
			(hide yes)
			(effects
				(font
					(size 1.27 1.27)
				)
			)
		)
		(property "Value" "4K7R2F-GP"
			(at 0.064008 -3.993896 90)
			(unlocked yes)
			(layer "F.Fab")
			(hide yes)
			(effects
				(font
					(size 1.016 1.016)
					(thickness 0.1524)
				)
			)
		)
		(property "Device Type" "R402H16"
			(at 0.064008 -5.517896 90)
			(unlocked yes)
			(layer "F.Fab")
			(hide yes)
			(effects
				(font
					(size 1.016 1.016)
					(thickness 0.1524)
				)
			)
		)
		(duplicate_pad_numbers_are_jumpers no)
		(fp_line
			(start 0.508 -0.9398)
			(end -0.508 -0.9398)
			(stroke
				(width 0.1524)
				(type default)
			)
			(layer "F.SilkS")
		)
		(fp_line
			(start -0.508 -0.9398)
			(end -0.508 0.9398)
			(stroke
				(width 0.1524)
				(type default)
			)
			(layer "F.SilkS")
		)
		(fp_rect
			(start -0.508 0.9398)
			(end 0.508 -0.9398)
			(stroke
				(width 0)
				(type default)
			)
			(fill no)
			(layer "F.CrtYd")
		)
		(fp_rect
			(start -0.508 0.9398)
			(end 0.508 -0.9398)
			(stroke
				(width 0)
				(type default)
			)
			(fill no)
			(layer "F.Fab")
		)
		(pad "1" smd custom
			(at 0 -0.4445 90)
			(size 0.1397 0.1397)
			(layers "F.Cu" "F.Mask" "F.Paste")
			(net "BMC_ADD1_GND")
			(options
				(clearance outline)
				(anchor circle)
			)
			(primitives
				(gr_poly
					(pts
						(arc
							(start -0.1778 -0.2794)
							(mid -0.249642 -0.249642)
							(end -0.2794 -0.1778)
						)
						(arc
							(start -0.2794 0.1778)
							(mid -0.249642 0.249642)
							(end -0.1778 0.2794)
						)
						(arc
							(start 0.1778 0.2794)
							(mid 0.249642 0.249642)
							(end 0.2794 0.1778)
						)
						(arc
							(start 0.2794 -0.1778)
							(mid 0.249642 -0.249642)
							(end 0.1778 -0.2794)
						)
					)
					(width 0)
					(fill yes)
				)
			)
		)
		(pad "2" smd custom
			(at 0 0.4445 90)
			(size 0.1397 0.1397)
			(layers "F.Cu" "F.Mask" "F.Paste")
			(net "GND")
			(options
				(clearance outline)
				(anchor circle)
			)
			(primitives
				(gr_poly
					(pts
						(arc
							(start -0.1778 -0.2794)
							(mid -0.249642 -0.249642)
							(end -0.2794 -0.1778)
						)
						(arc
							(start -0.2794 0.1778)
							(mid -0.249642 0.249642)
							(end -0.1778 0.2794)
						)
						(arc
							(start 0.1778 0.2794)
							(mid 0.249642 0.249642)
							(end 0.2794 0.1778)
						)
						(arc
							(start 0.2794 -0.1778)
							(mid 0.249642 -0.249642)
							(end 0.1778 -0.2794)
						)
					)
					(width 0)
					(fill yes)
				)
			)
		)
	)
	(footprint ""
		(layer "F.Cu")
		(at 51.816 -200.914)
		(property "Reference" "R894"
			(at 0 0 0)
			(layer "F.SilkS")
			(hide yes)
			(effects
				(font
					(size 1.27 1.27)
				)
			)
		)
		(property "Value" "0R2J-2-GP"
			(at 0.064008 -3.993896 0)
			(unlocked yes)
			(layer "F.Fab")
			(hide yes)
			(effects
				(font
					(size 1.016 1.016)
					(thickness 0.1524)
				)
			)
		)
		(property "Device Type" "R402H16"
			(at 0.064008 -5.517896 0)
			(unlocked yes)
			(layer "F.Fab")
			(hide yes)
			(effects
				(font
					(size 1.016 1.016)
					(thickness 0.1524)
				)
			)
		)
		(duplicate_pad_numbers_are_jumpers no)
		(fp_line
			(start -0.508 -0.9398)
			(end -0.508 0.9398)
			(stroke
				(width 0.1524)
				(type default)
			)
			(layer "F.SilkS")
		)
		(fp_line
			(start 0.508 -0.9398)
			(end -0.508 -0.9398)
			(stroke
				(width 0.1524)
				(type default)
			)
			(layer "F.SilkS")
		)
		(fp_rect
			(start -0.508 0.9398)
			(end 0.508 -0.9398)
			(stroke
				(width 0)
				(type default)
			)
			(fill no)
			(layer "F.CrtYd")
		)
		(fp_rect
			(start -0.508 0.9398)
			(end 0.508 -0.9398)
			(stroke
				(width 0)
				(type default)
			)
			(fill no)
			(layer "F.Fab")
		)
		(pad "1" smd custom
			(at 0 -0.4445)
			(size 0.1397 0.1397)
			(layers "F.Cu" "F.Mask" "F.Paste")
			(net "BUF_I2C7_B_DBP_SCL")
			(options
				(clearance outline)
				(anchor circle)
			)
			(primitives
				(gr_poly
					(pts
						(arc
							(start -0.1778 -0.2794)
							(mid -0.249642 -0.249642)
							(end -0.2794 -0.1778)
						)
						(arc
							(start -0.2794 0.1778)
							(mid -0.249642 0.249642)
							(end -0.1778 0.2794)
						)
						(arc
							(start 0.1778 0.2794)
							(mid 0.249642 0.249642)
							(end 0.2794 0.1778)
						)
						(arc
							(start 0.2794 -0.1778)
							(mid 0.249642 -0.249642)
							(end 0.1778 -0.2794)
						)
					)
					(width 0)
					(fill yes)
				)
			)
		)
		(pad "2" smd custom
			(at 0 0.4445)
			(size 0.1397 0.1397)
			(layers "F.Cu" "F.Mask" "F.Paste")
			(net "BUF_I2C7_B_DBP_SCL_R")
			(options
				(clearance outline)
				(anchor circle)
			)
			(primitives
				(gr_poly
					(pts
						(arc
							(start -0.1778 -0.2794)
							(mid -0.249642 -0.249642)
							(end -0.2794 -0.1778)
						)
						(arc
							(start -0.2794 0.1778)
							(mid -0.249642 0.249642)
							(end -0.1778 0.2794)
						)
						(arc
							(start 0.1778 0.2794)
							(mid 0.249642 0.249642)
							(end 0.2794 0.1778)
						)
						(arc
							(start 0.2794 -0.1778)
							(mid 0.249642 -0.249642)
							(end 0.1778 -0.2794)
						)
					)
					(width 0)
					(fill yes)
				)
			)
		)
	)
	(footprint ""
		(layer "F.Cu")
		(at 65.8622 -161.5186 -90)
		(property "Reference" "PU4"
			(at 0 0 270)
			(layer "F.SilkS")
			(hide yes)
			(effects
				(font
					(size 1.27 1.27)
				)
			)
		)
		(property "Value" "TPS74801DRCR-1-GP-U"
			(at -3.5306 1.3208 270)
			(unlocked yes)
			(layer "F.Fab")
			(hide yes)
			(effects
				(font
					(size 1.016 1.016)
					(thickness 0.1524)
				)
			)
		)
		(property "Device Type" "DFN10G3-G315175H40"
			(at -3.5306 -0.2032 270)
			(unlocked yes)
			(layer "F.Fab")
			(hide yes)
			(effects
				(font
					(size 1.016 1.016)
					(thickness 0.1524)
				)
			)
		)
		(duplicate_pad_numbers_are_jumpers no)
		(fp_line
			(start -2.3876 2.5146)
			(end -1.6256 2.5146)
			(stroke
				(width 0.1524)
				(type default)
			)
			(layer "F.SilkS")
		)
		(fp_line
			(start 1.6256 2.5146)
			(end 2.3876 2.5146)
			(stroke
				(width 0.1524)
				(type default)
			)
			(layer "F.SilkS")
		)
		(fp_line
			(start 2.3876 2.5146)
			(end 2.3876 1.7526)
			(stroke
				(width 0.1524)
				(type default)
			)
			(layer "F.SilkS")
		)
		(fp_line
			(start 0.9906 2.286)
			(end 0.9906 3.048)
			(stroke
				(width 0.1524)
				(type default)
			)
			(layer "F.SilkS")
		)
		(fp_line
			(start -2.3876 1.7526)
			(end -2.3876 2.5146)
			(stroke
				(width 0.1524)
				(type default)
			)
			(layer "F.SilkS")
		)
		(fp_line
			(start -2.3876 -2.5146)
			(end -2.3876 -1.7526)
			(stroke
				(width 0.1524)
				(type default)
			)
			(layer "F.SilkS")
		)
		(fp_line
			(start -1.6256 -2.5146)
			(end -2.3876 -2.5146)
			(stroke
				(width 0.1524)
				(type default)
			)
			(layer "F.SilkS")
		)
		(fp_line
			(start -0.9906 -2.794)
			(end -0.9906 -2.286)
			(stroke
				(width 0.1524)
				(type default)
			)
			(layer "F.SilkS")
		)
		(fp_poly
			(pts
				(xy 1.6256 -2.5146) (xy 2.3876 -2.5146) (xy 2.3876 -1.7526)
			)
			(stroke
				(width 0)
				(type default)
			)
			(fill yes)
			(layer "F.SilkS")
		)
		(fp_rect
			(start -1.4986 1.4986)
			(end 1.4986 -1.4986)
			(stroke
				(width 0)
				(type default)
			)
			(fill no)
			(layer "F.CrtYd")
		)
		(fp_poly
			(pts
				(xy -2.3876 2.5146) (xy -2.3876 0.00254) (xy -1.4986 0.00254) (xy -1.4986 1.4986) (xy 1.4986 1.4986)
				(xy 1.4986 -1.4986) (xy -1.4986 -1.4986) (xy -1.4986 -0.00254) (xy -2.3876 -0.00254) (xy -2.3876 -2.5146)
				(xy 2.3876 -2.5146) (xy 2.3876 2.5146)
			)
			(stroke
				(width 0)
				(type default)
			)
			(fill no)
			(layer "F.CrtYd")
		)
		(fp_rect
			(start -2.3876 2.5146)
			(end 2.3876 -2.5146)
			(stroke
				(width 0)
				(type default)
			)
			(fill no)
			(layer "F.Fab")
		)
		(pad "1" smd rect
			(at 0.99949 -1.5494 270)
			(size 0.3048 0.9144)
			(layers "F.Cu" "F.Mask" "F.Paste")
			(net "VR_P1V538_STBY_IN")
		)
		(pad "2" smd rect
			(at 0.50038 -1.5494 270)
			(size 0.3048 0.9144)
			(layers "F.Cu" "F.Mask" "F.Paste")
			(net "VR_P1V538_STBY_IN")
		)
		(pad "3" smd rect
			(at 0 -1.5494 270)
			(size 0.3048 0.9144)
			(layers "F.Cu" "F.Mask" "F.Paste")
			(net "PWRGD_P1V538_STBY")
		)
		(pad "4" smd rect
			(at -0.50038 -1.5494 270)
			(size 0.3048 0.9144)
			(layers "F.Cu" "F.Mask" "F.Paste")
			(net "VR_P1V538_STBY_BIAS")
		)
		(pad "5" smd rect
			(at -0.99949 -1.5494 270)
			(size 0.3048 0.9144)
			(layers "F.Cu" "F.Mask" "F.Paste")
			(net "VR_P1V538_STBY_EN_R")
		)
		(pad "6" smd rect
			(at -0.99949 1.5494 270)
			(size 0.3048 0.9144)
			(layers "F.Cu" "F.Mask" "F.Paste")
			(net "GND")
		)
		(pad "7" smd rect
			(at -0.50038 1.5494 270)
			(size 0.3048 0.9144)
			(layers "F.Cu" "F.Mask" "F.Paste")
			(net "VR_P1V538_STBY_SS_C")
		)
		(pad "8" smd rect
			(at 0 1.5494 270)
			(size 0.3048 0.9144)
			(layers "F.Cu" "F.Mask" "F.Paste")
			(net "VR_P1V538_STBY_FB")
		)
		(pad "9" smd rect
			(at 0.50038 1.5494 270)
			(size 0.3048 0.9144)
			(layers "F.Cu" "F.Mask" "F.Paste")
			(net "P1V53_PWR")
		)
		(pad "10" smd rect
			(at 0.99949 1.5494 270)
			(size 0.3048 0.9144)
			(layers "F.Cu" "F.Mask" "F.Paste")
			(net "P1V53_PWR")
		)
		(pad "11" smd custom
			(at 0 0 270)
			(size 0.4318 0.4318)
			(layers "F.Cu" "F.Mask" "F.Paste")
			(net "GND")
			(options
				(clearance outline)
				(anchor circle)
			)
			(primitives
				(gr_poly
					(pts
						(xy -1.2446 0.8636) (xy -1.2446 0.3937) (xy -1.8796 0.3937) (xy -1.8796 0.1143) (xy -1.2446 0.1143)
						(xy -1.2446 -0.1143) (xy -1.8796 -0.1143) (xy -1.8796 -0.3937) (xy -1.2446 -0.3937) (xy -1.2446 -0.8636)
						(xy 1.2446 -0.8636) (xy 1.2446 -0.3937) (xy 1.8796 -0.3937) (xy 1.8796 -0.1143) (xy 1.2446 -0.1143)
						(xy 1.2446 0.1143) (xy 1.8796 0.1143) (xy 1.8796 0.3937) (xy 1.2446 0.3937) (xy 1.2446 0.8636)
					)
					(width 0)
					(fill yes)
				)
			)
		)
	)
)
